(kicad_pcb
	(version 20260206)
	(generator "pcbnew")
	(generator_version "10.0")
	(general
		(thickness 1.6)
		(legacy_teardrops no)
	)
	(paper "A4")
	(title_block
		(title "timecard-production-celestica-r4006 — R4006-B0001-02_R01.brd")
		(comment 1 "Time Appliance Project (Time Card) / footprints 240-245 of 1113")
	)
	(layers
		(0 "F.Cu" signal "TOP")
		(4 "In1.Cu" signal "L02_GND1")
		(6 "In2.Cu" signal "L03_SIG1")
		(8 "In3.Cu" signal "L04_GND2")
		(10 "In4.Cu" signal "L05_VCC1")
		(12 "In5.Cu" signal "L06_VCC2")
		(14 "In6.Cu" signal "L07_GND3")
		(16 "In7.Cu" signal "L08_SIG2")
		(18 "In8.Cu" signal "L09_GND4")
		(2 "B.Cu" signal "BOTTOM")
		(9 "F.Adhes" user "F.Adhesive")
		(11 "B.Adhes" user "B.Adhesive")
		(13 "F.Paste" user "Package Geometry/Pastemask Top")
		(15 "B.Paste" user "Package Geometry/Pastemask Bottom")
		(5 "F.SilkS" user "Ref Des/Silkscreen Top")
		(7 "B.SilkS" user "Ref Des/Silkscreen Bottom")
		(1 "F.Mask" user "Board Geometry/Soldermask Top")
		(3 "B.Mask" user "Board Geometry/Soldermask Bottom")
		(17 "Dwgs.User" user "User.Drawings")
		(19 "Cmts.User" user "User.Comments")
		(21 "Eco1.User" user "User.Eco1")
		(23 "Eco2.User" user "User.Eco2")
		(25 "Edge.Cuts" user "Board Geometry/Outline")
		(27 "Margin" user)
		(31 "F.CrtYd" user "Package Geometry/Place Bound Top")
		(29 "B.CrtYd" user "Package Geometry/Place Bound Bottom")
		(35 "F.Fab" user "Ref Des/Assembly Top")
		(33 "B.Fab" user "Ref Des/Assembly Bottom")
	)
	(footprint ""
		(layer "F.Cu")
		(at 138.050016 -104.350058 -90)
		(property "Reference" "DS6"
			(at 0.845058 1.993646 90)
			(unlocked yes)
			(layer "F.SilkS")
			(effects
				(font
					(size 0.7874 0.5842)
					(thickness 0.1524)
				)
			)
		)
		(property "Value" ""
			(at 0 0 270)
			(layer "F.Fab")
			(effects
				(font
					(size 1.27 1.27)
				)
			)
		)
		(property "Device Type" "OPTICAL-G170-10143-01"
			(at 0.1778 1.483081 270)
			(unlocked yes)
			(layer "F.Fab")
			(hide yes)
			(effects
				(font
					(size 0.786892 0.583946)
					(thickness 0.000001)
				)
			)
		)
		(property "User Part Number" "PARTNUM*"
			(at 0.1778 2.422881 270)
			(unlocked yes)
			(layer "Cmts.User")
			(hide yes)
			(effects
				(font
					(size 0.786892 0.583946)
					(thickness 0.000001)
				)
			)
		)
		(duplicate_pad_numbers_are_jumpers no)
		(fp_line
			(start -0.8128 1.8542)
			(end -2.0828 1.8542)
			(stroke
				(width 0.1)
				(type default)
			)
			(layer "F.SilkS")
		)
		(fp_line
			(start -1.4478 1.2192)
			(end -1.4478 2.4892)
			(stroke
				(width 0.1)
				(type default)
			)
			(layer "F.SilkS")
		)
		(fp_line
			(start -1.397508 0.704088)
			(end -1.397508 -0.704088)
			(stroke
				(width 0.1)
				(type default)
			)
			(layer "F.SilkS")
		)
		(fp_line
			(start 1.397508 0.704088)
			(end -1.397508 0.704088)
			(stroke
				(width 0.1)
				(type default)
			)
			(layer "F.SilkS")
		)
		(fp_line
			(start -1.397508 -0.704088)
			(end 1.397508 -0.704088)
			(stroke
				(width 0.1)
				(type default)
			)
			(layer "F.SilkS")
		)
		(fp_line
			(start 1.397508 -0.704088)
			(end 1.397508 0.704088)
			(stroke
				(width 0.1)
				(type default)
			)
			(layer "F.SilkS")
		)
		(fp_rect
			(start 1.905508 0.704088)
			(end 1.397508 -0.704088)
			(stroke
				(width 0)
				(type default)
			)
			(fill yes)
			(layer "F.SilkS")
		)
		(fp_rect
			(start 1.905508 0.958088)
			(end -1.651508 -0.958088)
			(stroke
				(width 0)
				(type default)
			)
			(fill no)
			(layer "F.CrtYd")
		)
		(fp_line
			(start -1.1938 1.4732)
			(end -2.4638 1.4732)
			(stroke
				(width 0.1)
				(type default)
			)
			(layer "F.Fab")
		)
		(fp_line
			(start -1.8288 0.8382)
			(end -1.8288 2.1082)
			(stroke
				(width 0.1)
				(type default)
			)
			(layer "F.Fab")
		)
		(fp_line
			(start -0.850138 0.450088)
			(end 0.850138 0.450088)
			(stroke
				(width 0.1)
				(type default)
			)
			(layer "F.Fab")
		)
		(fp_line
			(start 0.850138 0.450088)
			(end 0.850138 -0.450088)
			(stroke
				(width 0.1)
				(type default)
			)
			(layer "F.Fab")
		)
		(fp_line
			(start -0.850138 -0.450088)
			(end -0.850138 0.450088)
			(stroke
				(width 0.1)
				(type default)
			)
			(layer "F.Fab")
		)
		(fp_line
			(start 0.850138 -0.450088)
			(end -0.850138 -0.450088)
			(stroke
				(width 0.1)
				(type default)
			)
			(layer "F.Fab")
		)
		(fp_rect
			(start 0.850138 0.450088)
			(end 0.342138 -0.450088)
			(stroke
				(width 0)
				(type default)
			)
			(fill yes)
			(layer "F.Fab")
		)
		(fp_text user "A"
			(at -0.774192 1.652016 0)
			(unlocked yes)
			(layer "F.SilkS")
			(effects
				(font
					(size 0.635 0.4064)
					(thickness 0.1524)
				)
			)
		)
		(fp_text user "C"
			(at 1.892808 1.271016 0)
			(unlocked yes)
			(layer "F.SilkS")
			(effects
				(font
					(size 0.635 0.4064)
					(thickness 0.1524)
				)
			)
		)
		(fp_text user "A"
			(at -1.020572 0.890016 0)
			(unlocked yes)
			(layer "F.Fab")
			(effects
				(font
					(size 0.7874 0.5842)
					(thickness 0.1524)
				)
			)
		)
		(fp_text user "C"
			(at 1.773428 0.128016 0)
			(unlocked yes)
			(layer "F.Fab")
			(effects
				(font
					(size 0.7874 0.5842)
					(thickness 0.1524)
				)
			)
		)
		(pad "A" smd rect
			(at -0.749808 0 270)
			(size 0.7874 0.7874)
			(layers "F.Cu" "F.Mask" "F.Paste")
			(net "UNNAMED_14_OPTICAL_I140_A")
		)
		(pad "C" smd rect
			(at 0.749808 0 270)
			(size 0.7874 0.7874)
			(layers "F.Cu" "F.Mask" "F.Paste")
			(net "SG")
		)
	)
	(footprint ""
		(layer "F.Cu")
		(at 42.6974 -105.4354)
		(property "Reference" "C30"
			(at 3.6576 -1.21793 0)
			(unlocked yes)
			(layer "F.SilkS")
			(effects
				(font
					(size 0.7874 0.5842)
					(thickness 0.1524)
				)
			)
		)
		(property "Value" "VAL*"
			(at 0.0762 3.134106 0)
			(unlocked yes)
			(layer "F.Fab")
			(hide yes)
			(effects
				(font
					(size 0.7874 0.5842)
					(thickness 0.1524)
				)
			)
		)
		(property "Device Type" "CAPACITOR-G107-0F106-EM,10UF,2A"
			(at 0.0508 2.194306 0)
			(unlocked yes)
			(layer "F.Fab")
			(hide yes)
			(effects
				(font
					(size 0.7874 0.5842)
					(thickness 0.1524)
				)
			)
		)
		(property "User Part Number" "PARTNUM*"
			(at 0.1016 5.013706 0)
			(unlocked yes)
			(layer "Cmts.User")
			(hide yes)
			(effects
				(font
					(size 0.7874 0.5842)
					(thickness 0.1524)
				)
			)
		)
		(property "Tolerance" "TOL*"
			(at 0.0762 4.048506 0)
			(unlocked yes)
			(layer "Cmts.User")
			(hide yes)
			(effects
				(font
					(size 0.7874 0.5842)
					(thickness 0.1524)
				)
			)
		)
		(duplicate_pad_numbers_are_jumpers no)
		(fp_line
			(start -1.5748 -0.9398)
			(end -1.5748 0.9398)
			(stroke
				(width 0.1)
				(type default)
			)
			(layer "F.SilkS")
		)
		(fp_line
			(start -1.5748 0.9398)
			(end 1.5748 0.9398)
			(stroke
				(width 0.1)
				(type default)
			)
			(layer "F.SilkS")
		)
		(fp_line
			(start 1.5748 -0.9398)
			(end -1.5748 -0.9398)
			(stroke
				(width 0.1)
				(type default)
			)
			(layer "F.SilkS")
		)
		(fp_line
			(start 1.5748 0.9398)
			(end 1.5748 -0.9398)
			(stroke
				(width 0.1)
				(type default)
			)
			(layer "F.SilkS")
		)
		(fp_rect
			(start 1.5748 -0.9398)
			(end -1.5748 0.9398)
			(stroke
				(width 0)
				(type default)
			)
			(fill no)
			(layer "F.CrtYd")
		)
		(fp_line
			(start -1.016 -0.635)
			(end -1.016 0.635)
			(stroke
				(width 0.1)
				(type default)
			)
			(layer "F.Fab")
		)
		(fp_line
			(start -1.016 0.635)
			(end 1.016 0.635)
			(stroke
				(width 0.1)
				(type default)
			)
			(layer "F.Fab")
		)
		(fp_line
			(start 1.016 -0.635)
			(end -1.016 -0.635)
			(stroke
				(width 0.1)
				(type default)
			)
			(layer "F.Fab")
		)
		(fp_line
			(start 1.016 0.635)
			(end 1.016 -0.635)
			(stroke
				(width 0.1)
				(type default)
			)
			(layer "F.Fab")
		)
		(pad "1" smd rect
			(at -0.8382 0)
			(size 0.9652 1.3716)
			(layers "F.Cu" "F.Mask" "F.Paste")
			(net "VIN_XP5R0V")
		)
		(pad "2" smd rect
			(at 0.8382 0)
			(size 0.9652 1.3716)
			(layers "F.Cu" "F.Mask" "F.Paste")
			(net "SG")
		)
		(zone
			(layer "F.Cu")
			(hatch none 0.5)
			(connect_pads
				(clearance 0)
			)
			(min_thickness 0.25)
			(keepout
				(tracks allowed)
				(vias not_allowed)
				(pads allowed)
				(copperpour not_allowed)
				(footprints allowed)
			)
			(placement
				(enabled no)
				(sheetname "")
			)
			(fill
				(thermal_gap 0.5)
				(thermal_bridge_width 0.5)
				(island_removal_mode 0)
			)
			(polygon
				(pts
					(xy 42.926 -106.0704) (xy 42.4688 -106.0704) (xy 42.4688 -104.8004) (xy 42.926 -104.8004)
				)
			)
		)
	)
	(footprint ""
		(layer "F.Cu")
		(at 111.887 -93.98)
		(property "Reference" "R452"
			(at 3.175 -0.08763 0)
			(unlocked yes)
			(layer "F.SilkS")
			(effects
				(font
					(size 0.7874 0.5842)
					(thickness 0.1524)
				)
			)
		)
		(property "Value" "VAL*"
			(at 0.02032 2.13233 0)
			(unlocked yes)
			(layer "F.Fab")
			(hide yes)
			(effects
				(font
					(size 0.7874 0.5842)
					(thickness 0.1524)
				)
			)
		)
		(property "Tolerance" "TOL*"
			(at 0.044704 3.05435 0)
			(unlocked yes)
			(layer "Cmts.User")
			(hide yes)
			(effects
				(font
					(size 0.7874 0.5842)
					(thickness 0.1524)
				)
			)
		)
		(property "User Part Number" "PARTNUM*"
			(at 0.02032 4.024884 0)
			(unlocked yes)
			(layer "Cmts.User")
			(hide yes)
			(effects
				(font
					(size 0.7874 0.5842)
					(thickness 0.1524)
				)
			)
		)
		(property "Device Type" "RESISTOR-G155-14701-01,4.7KOHMA"
			(at 0.008382 1.210564 0)
			(unlocked yes)
			(layer "F.Fab")
			(hide yes)
			(effects
				(font
					(size 0.7874 0.5842)
					(thickness 0.1524)
				)
			)
		)
		(duplicate_pad_numbers_are_jumpers no)
		(fp_line
			(start -1.143 -0.5588)
			(end -1.143 0.5588)
			(stroke
				(width 0.1)
				(type default)
			)
			(layer "F.SilkS")
		)
		(fp_line
			(start -1.143 0.5588)
			(end 1.143 0.5588)
			(stroke
				(width 0.1)
				(type default)
			)
			(layer "F.SilkS")
		)
		(fp_line
			(start 1.143 -0.5588)
			(end -1.143 -0.5588)
			(stroke
				(width 0.1)
				(type default)
			)
			(layer "F.SilkS")
		)
		(fp_line
			(start 1.143 0.5588)
			(end 1.143 -0.5588)
			(stroke
				(width 0.1)
				(type default)
			)
			(layer "F.SilkS")
		)
		(fp_poly
			(pts
				(xy -1.143 0.5588) (xy 1.143 0.5588) (xy 1.143 -0.5588) (xy -1.143 -0.5588)
			)
			(stroke
				(width 0)
				(type default)
			)
			(fill no)
			(layer "F.CrtYd")
		)
		(fp_line
			(start -0.508 -0.3048)
			(end -0.508 0.3048)
			(stroke
				(width 0.1)
				(type default)
			)
			(layer "F.Fab")
		)
		(fp_line
			(start -0.508 0.3048)
			(end 0.508 0.3048)
			(stroke
				(width 0.1)
				(type default)
			)
			(layer "F.Fab")
		)
		(fp_line
			(start 0.508 -0.3048)
			(end -0.508 -0.3048)
			(stroke
				(width 0.1)
				(type default)
			)
			(layer "F.Fab")
		)
		(fp_line
			(start 0.508 0.3048)
			(end 0.508 -0.3048)
			(stroke
				(width 0.1)
				(type default)
			)
			(layer "F.Fab")
		)
		(pad "1" smd rect
			(at -0.5334 0)
			(size 0.7112 0.6096)
			(layers "F.Cu" "F.Mask" "F.Paste")
			(net "UNNAMED_524_POWERMOS3PNCHV1_I44")
		)
		(pad "2" smd rect
			(at 0.5334 0)
			(size 0.7112 0.6096)
			(layers "F.Cu" "F.Mask" "F.Paste")
			(net "XP3R3V_FPGA")
		)
		(zone
			(layer "F.Cu")
			(hatch none 0.5)
			(connect_pads
				(clearance 0)
			)
			(min_thickness 0.25)
			(keepout
				(tracks allowed)
				(vias not_allowed)
				(pads allowed)
				(copperpour not_allowed)
				(footprints allowed)
			)
			(placement
				(enabled no)
				(sheetname "")
			)
			(fill
				(thermal_gap 0.5)
				(thermal_bridge_width 0.5)
				(island_removal_mode 0)
			)
			(polygon
				(pts
					(xy 111.8108 -93.6752) (xy 111.9632 -93.6752) (xy 111.9632 -94.2848) (xy 111.8108 -94.2848)
				)
			)
		)
		(zone
			(layer "F.Cu")
			(hatch none 0.5)
			(connect_pads
				(clearance 0)
			)
			(min_thickness 0.25)
			(keepout
				(tracks not_allowed)
				(vias allowed)
				(pads allowed)
				(copperpour not_allowed)
				(footprints allowed)
			)
			(placement
				(enabled no)
				(sheetname "")
			)
			(fill
				(thermal_gap 0.5)
				(thermal_bridge_width 0.5)
				(island_removal_mode 0)
			)
			(polygon
				(pts
					(xy 111.8108 -93.6752) (xy 111.9632 -93.6752) (xy 111.9632 -94.2848) (xy 111.8108 -94.2848)
				)
			)
		)
	)
	(footprint ""
		(layer "F.Cu")
		(at 106.807 -20.828)
		(property "Reference" "TP49"
			(at 0.03937 4.5212 90)
			(unlocked yes)
			(layer "F.SilkS")
			(effects
				(font
					(size 0.7874 0.5842)
					(thickness 0.1524)
				)
				(justify left)
			)
		)
		(property "Value" ""
			(at 0 0 0)
			(layer "F.Fab")
			(effects
				(font
					(size 1.27 1.27)
				)
			)
		)
		(property "Device Type" "TP_PIONT-TP010CT020B030_PTH-TPA"
			(at -1.341882 0.996696 0)
			(unlocked yes)
			(layer "F.Fab")
			(hide yes)
			(effects
				(font
					(size 0.7874 0.5842)
					(thickness 0.000001)
				)
				(justify left)
			)
		)
		(duplicate_pad_numbers_are_jumpers no)
		(fp_poly
			(pts
				(arc
					(start 0.889 0)
					(mid -0.889 0)
					(end 0.889 0)
				)
			)
			(stroke
				(width 0)
				(type default)
			)
			(fill no)
			(layer "B.CrtYd")
		)
		(fp_poly
			(pts
				(arc
					(start 0.889 0)
					(mid -0.889 0)
					(end 0.889 0)
				)
			)
			(stroke
				(width 0)
				(type default)
			)
			(fill no)
			(layer "F.CrtYd")
		)
		(pad "1" thru_hole circle
			(at 0 0)
			(size 0.508 0.508)
			(drill 0.254)
			(layers "*.Cu" "*.Mask")
			(remove_unused_layers no)
			(net "CLK_200M_OE")
			(clearance 0.1016)
			(padstack
				(mode front_inner_back)
				(layer "Inner"
					(shape circle)
					(size 0.508 0.508)
					(clearance 0.1016)
				)
				(layer "B.Cu"
					(shape circle)
					(size 0.762 0.762)
					(clearance -0.0254)
				)
			)
		)
	)
	(footprint ""
		(layer "F.Cu")
		(at 141.732 -100.584 180)
		(property "Reference" "R13"
			(at -2.032 -0.66675 0)
			(unlocked yes)
			(layer "F.SilkS")
			(effects
				(font
					(size 0.635 0.4064)
					(thickness 0.1524)
				)
			)
		)
		(property "Value" "VAL*"
			(at 0.02032 2.13233 180)
			(unlocked yes)
			(layer "F.Fab")
			(hide yes)
			(effects
				(font
					(size 0.7874 0.5842)
					(thickness 0.1524)
				)
			)
		)
		(property "Device Type" "RESISTOR-G155-11002-01,10KOHM,A"
			(at 0.008382 1.210564 180)
			(unlocked yes)
			(layer "F.Fab")
			(hide yes)
			(effects
				(font
					(size 0.7874 0.5842)
					(thickness 0.1524)
				)
			)
		)
		(property "User Part Number" "PARTNUM*"
			(at 0.02032 4.024884 180)
			(unlocked yes)
			(layer "Cmts.User")
			(hide yes)
			(effects
				(font
					(size 0.7874 0.5842)
					(thickness 0.1524)
				)
			)
		)
		(property "Tolerance" "TOL*"
			(at 0.044704 3.05435 180)
			(unlocked yes)
			(layer "Cmts.User")
			(hide yes)
			(effects
				(font
					(size 0.7874 0.5842)
					(thickness 0.1524)
				)
			)
		)
		(duplicate_pad_numbers_are_jumpers no)
		(fp_line
			(start 1.143 0.5588)
			(end 1.143 -0.5588)
			(stroke
				(width 0.1)
				(type default)
			)
			(layer "F.SilkS")
		)
		(fp_line
			(start 1.143 -0.5588)
			(end -1.143 -0.5588)
			(stroke
				(width 0.1)
				(type default)
			)
			(layer "F.SilkS")
		)
		(fp_line
			(start -1.143 0.5588)
			(end 1.143 0.5588)
			(stroke
				(width 0.1)
				(type default)
			)
			(layer "F.SilkS")
		)
		(fp_line
			(start -1.143 -0.5588)
			(end -1.143 0.5588)
			(stroke
				(width 0.1)
				(type default)
			)
			(layer "F.SilkS")
		)
		(fp_rect
			(start -1.143 0.5588)
			(end 1.143 -0.5588)
			(stroke
				(width 0)
				(type default)
			)
			(fill no)
			(layer "F.CrtYd")
		)
		(fp_line
			(start 0.508 0.3048)
			(end 0.508 -0.3048)
			(stroke
				(width 0.1)
				(type default)
			)
			(layer "F.Fab")
		)
		(fp_line
			(start 0.508 -0.3048)
			(end -0.508 -0.3048)
			(stroke
				(width 0.1)
				(type default)
			)
			(layer "F.Fab")
		)
		(fp_line
			(start -0.508 0.3048)
			(end 0.508 0.3048)
			(stroke
				(width 0.1)
				(type default)
			)
			(layer "F.Fab")
		)
		(fp_line
			(start -0.508 -0.3048)
			(end -0.508 0.3048)
			(stroke
				(width 0.1)
				(type default)
			)
			(layer "F.Fab")
		)
		(pad "1" smd rect
			(at -0.5334 0 180)
			(size 0.7112 0.6096)
			(layers "F.Cu" "F.Mask" "F.Paste")
			(net "XP12R0V")
		)
		(pad "2" smd rect
			(at 0.5334 0 180)
			(size 0.7112 0.6096)
			(layers "F.Cu" "F.Mask" "F.Paste")
			(net "XP12R0V_A_PG")
		)
		(zone
			(layer "F.Cu")
			(hatch none 0.5)
			(connect_pads
				(clearance 0)
			)
			(min_thickness 0.25)
			(keepout
				(tracks allowed)
				(vias not_allowed)
				(pads allowed)
				(copperpour not_allowed)
				(footprints allowed)
			)
			(placement
				(enabled no)
				(sheetname "")
			)
			(fill
				(thermal_gap 0.5)
				(thermal_bridge_width 0.5)
				(island_removal_mode 0)
			)
			(polygon
				(pts
					(xy 141.8082 -100.8888) (xy 141.6558 -100.8888) (xy 141.6558 -100.2792) (xy 141.8082 -100.2792)
				)
			)
		)
	)
	(footprint ""
		(layer "F.Cu")
		(at 37.101018 -68.082922)
		(property "Reference" "ME5"
			(at -1.795018 -4.140708 0)
			(unlocked yes)
			(layer "F.SilkS")
			(effects
				(font
					(size 0.7874 0.5842)
					(thickness 0.1524)
				)
			)
		)
		(property "Value" ""
			(at 0 0 0)
			(layer "F.Fab")
			(effects
				(font
					(size 1.27 1.27)
				)
			)
		)
		(duplicate_pad_numbers_are_jumpers no)
		(fp_poly
			(pts
				(arc
					(start 3.556 0)
					(mid -3.556 0)
					(end 3.556 0)
				)
			)
			(stroke
				(width 0)
				(type default)
			)
			(fill no)
			(layer "B.CrtYd")
		)
		(fp_poly
			(pts
				(arc
					(start 3.556 0)
					(mid -3.556 0)
					(end 3.556 0)
				)
			)
			(stroke
				(width 0)
				(type default)
			)
			(fill no)
			(layer "F.CrtYd")
		)
		(fp_circle
			(center 0 0)
			(end 3.048 0)
			(stroke
				(width 0.1)
				(type default)
			)
			(fill no)
			(layer "B.Fab")
		)
		(fp_circle
			(center 0 0)
			(end 3.048 0)
			(stroke
				(width 0.1)
				(type default)
			)
			(fill no)
			(layer "F.Fab")
		)
		(pad "" np_thru_hole circle
			(at 0 0)
			(size 2.286 2.286)
			(drill 2.54)
			(layers "*.Cu" "*.Mask")
			(padstack
				(mode front_inner_back)
				(layer "Inner"
					(shape circle)
					(size 2.286 2.286)
					(clearance 0.4445)
				)
				(layer "B.Cu"
					(shape circle)
					(size 2.286 2.286)
				)
			)
		)
		(zone
			(layers "F.Cu" "B.Cu" "In1.Cu" "In2.Cu" "In3.Cu" "In4.Cu" "In5.Cu" "In6.Cu"
				"In7.Cu" "In8.Cu"
			)
			(hatch none 0.5)
			(connect_pads
				(clearance 0)
			)
			(min_thickness 0.25)
			(keepout
				(tracks not_allowed)
				(vias allowed)
				(pads allowed)
				(copperpour not_allowed)
				(footprints allowed)
			)
			(placement
				(enabled no)
				(sheetname "")
			)
			(fill
				(thermal_gap 0.5)
				(thermal_bridge_width 0.5)
				(island_removal_mode 0)
			)
			(polygon
				(pts
					(arc
						(start 38.675818 -68.082922)
						(mid 35.526218 -68.082922)
						(end 38.675818 -68.082922)
					)
				)
			)
		)
	)
)
